(kicad_pcb
	(version 20241229)
	(generator "pcbnew")
	(generator_version "9.0")
	(general
		(thickness 1.62)
		(legacy_teardrops no)
	)
	(paper "A3")
	(title_block
		(title "COM Express 7 Baseboard")
		(date "2025-02-04")
		(rev "1.1.2")
		(company "Antmicro Ltd")
		(comment 1 "www.antmicro.com")
		(comment 9 "footprints 481-485 of 802")
	)
	(layers
		(0 "F.Cu" signal)
		(4 "In1.Cu" signal)
		(6 "In2.Cu" signal)
		(8 "In3.Cu" signal)
		(10 "In4.Cu" signal)
		(12 "In5.Cu" signal)
		(14 "In6.Cu" signal)
		(2 "B.Cu" signal)
		(9 "F.Adhes" user "F.Adhesive")
		(11 "B.Adhes" user "B.Adhesive")
		(13 "F.Paste" user)
		(15 "B.Paste" user)
		(5 "F.SilkS" user "F.Silkscreen")
		(7 "B.SilkS" user "B.Silkscreen")
		(1 "F.Mask" user)
		(3 "B.Mask" user)
		(17 "Dwgs.User" user "User.Drawings")
		(19 "Cmts.User" user "User.Comments")
		(21 "Eco1.User" user "User.Eco1")
		(23 "Eco2.User" user "User.Eco2")
		(25 "Edge.Cuts" user)
		(27 "Margin" user)
		(31 "F.CrtYd" user "F.Courtyard")
		(29 "B.CrtYd" user "B.Courtyard")
		(35 "F.Fab" user)
		(33 "B.Fab" user)
	)
	(footprint "antmicro-footprints:R_0402_1005Metric"
		(layer "F.Cu")
		(at 160.55 156.81 -90)
		(descr "Resistor SMD 0402")
		(tags "resistor SMD 0402")
		(property "Reference" "R33"
			(at -3.013 -0.449 90)
			(layer "F.SilkS")
			(effects
				(font
					(size 0.7 0.7)
					(thickness 0.15)
				)
				(justify right bottom)
			)
		)
		(property "Value" "R_0R_0402"
			(at -1.011843 1.772047 90)
			(layer "F.Fab")
			(effects
				(font
					(size 0.7 0.7)
					(thickness 0.15)
				)
				(justify right bottom)
			)
		)
		(property "Datasheet" "https://industrial.panasonic.com/cdbs/www-data/pdf/RDA0000/AOA0000C301.pdf"
			(at 0 0 270)
			(layer "F.Fab")
			(hide yes)
			(effects
				(font
					(size 1.27 1.27)
					(thickness 0.15)
				)
			)
		)
		(property "Author" "Antmicro"
			(at 3.74 317.36 0)
			(layer "F.Fab")
			(hide yes)
			(effects
				(font
					(size 1 1)
					(thickness 0.15)
				)
			)
		)
		(property "Current" "1A"
			(at 3.74 317.36 0)
			(layer "F.Fab")
			(hide yes)
			(effects
				(font
					(size 1 1)
					(thickness 0.15)
				)
			)
		)
		(property "License" "Apache-2.0"
			(at 3.74 317.36 0)
			(layer "F.Fab")
			(hide yes)
			(effects
				(font
					(size 1 1)
					(thickness 0.15)
				)
			)
		)
		(property "MPN" "ERJ2GE0R00X"
			(at 3.74 317.36 0)
			(layer "F.Fab")
			(hide yes)
			(effects
				(font
					(size 1 1)
					(thickness 0.15)
				)
			)
		)
		(property "Manufacturer" "Panasonic"
			(at 3.74 317.36 0)
			(layer "F.Fab")
			(hide yes)
			(effects
				(font
					(size 1 1)
					(thickness 0.15)
				)
			)
		)
		(property "Public" "False"
			(at 3.74 317.36 0)
			(layer "F.Fab")
			(hide yes)
			(effects
				(font
					(size 1 1)
					(thickness 0.15)
				)
			)
		)
		(property "Tolerance" ""
			(at 3.74 317.36 0)
			(layer "F.Fab")
			(hide yes)
			(effects
				(font
					(size 1 1)
					(thickness 0.15)
				)
			)
		)
		(property "Val" "0R"
			(at 3.74 317.36 0)
			(layer "F.Fab")
			(hide yes)
			(effects
				(font
					(size 1 1)
					(thickness 0.15)
				)
			)
		)
		(sheetname "2xSFP+")
		(sheetfile "2xSFP+.kicad_sch")
		(attr smd)
		(fp_rect
			(start -0.925 -0.47)
			(end 0.925 0.47)
			(stroke
				(width 0.05)
				(type default)
			)
			(fill no)
			(layer "F.CrtYd")
		)
		(fp_rect
			(start -0.5 -0.25)
			(end 0.5 0.25)
			(stroke
				(width 0.15)
				(type solid)
			)
			(fill no)
			(layer "F.Fab")
		)
		(pad "1" smd roundrect
			(at -0.48 0 270)
			(size 0.59 0.64)
			(layers "F.Cu" "F.Mask" "F.Paste")
			(roundrect_rratio 0.25)
			(net 422 "/2xSFP+/I2C_{LED}.SDA")
			(pintype "passive")
			(teardrops
				(best_length_ratio 0.2)
				(max_length 1)
				(best_width_ratio 0.9)
				(max_width 2)
				(curved_edges yes)
				(filter_ratio 0.9)
				(enabled yes)
				(allow_two_segments yes)
				(prefer_zone_connections yes)
			)
		)
		(pad "2" smd roundrect
			(at 0.48 0 270)
			(size 0.59 0.64)
			(layers "F.Cu" "F.Mask" "F.Paste")
			(roundrect_rratio 0.25)
			(net 558 "Net-(U5-SDA)")
			(pintype "passive")
			(teardrops
				(best_length_ratio 0.2)
				(max_length 1)
				(best_width_ratio 0.9)
				(max_width 2)
				(curved_edges yes)
				(filter_ratio 0.9)
				(enabled yes)
				(allow_two_segments yes)
				(prefer_zone_connections yes)
			)
		)
	)
	(footprint "antmicro-footprints:LED_0603_1608Metric_Y"
		(layer "F.Cu")
		(at 138.63 156.17 180)
		(descr "LED SMD 0603 Yellow")
		(tags "LED SMD 0603 Yellow")
		(property "Reference" "D5"
			(at 2.68 -0.44 180)
			(layer "F.SilkS")
			(effects
				(font
					(size 0.7 0.7)
					(thickness 0.15)
				)
				(justify left bottom)
			)
		)
		(property "Value" "LED_Y_0603_LTST-C191KSKT"
			(at 0 1.6 180)
			(layer "F.Fab")
			(effects
				(font
					(size 0.7 0.7)
					(thickness 0.15)
				)
				(justify left bottom)
			)
		)
		(property "Datasheet" "https://optoelectronics.liteon.com/upload/download/DS22-2000-224/LTST-C191KSKT.PDF"
			(at 0 0 180)
			(layer "F.Fab")
			(hide yes)
			(effects
				(font
					(size 1.27 1.27)
					(thickness 0.15)
				)
			)
		)
		(property "Author" "Antmicro"
			(at 277.26 312.34 0)
			(layer "F.Fab")
			(hide yes)
			(effects
				(font
					(size 1 1)
					(thickness 0.15)
				)
			)
		)
		(property "Color" "Yellow"
			(at 277.26 312.34 0)
			(layer "F.Fab")
			(hide yes)
			(effects
				(font
					(size 1 1)
					(thickness 0.15)
				)
			)
		)
		(property "License" "Apache-2.0"
			(at 277.26 312.34 0)
			(layer "F.Fab")
			(hide yes)
			(effects
				(font
					(size 1 1)
					(thickness 0.15)
				)
			)
		)
		(property "MPN" "LTST-C191KSKT"
			(at 277.26 312.34 0)
			(layer "F.Fab")
			(hide yes)
			(effects
				(font
					(size 1 1)
					(thickness 0.15)
				)
			)
		)
		(property "Manufacturer" "Lite-On"
			(at 277.26 312.34 0)
			(layer "F.Fab")
			(hide yes)
			(effects
				(font
					(size 1 1)
					(thickness 0.15)
				)
			)
		)
		(sheetname "2xSFP+")
		(sheetfile "2xSFP+.kicad_sch")
		(attr smd)
		(fp_line
			(start 0.22 0.35)
			(end -0.22 0.35)
			(stroke
				(width 0.15)
				(type solid)
			)
			(layer "F.SilkS")
		)
		(fp_line
			(start 0.22 -0.35)
			(end -0.22 -0.35)
			(stroke
				(width 0.15)
				(type solid)
			)
			(layer "F.SilkS")
		)
		(fp_line
			(start 0.105328 0.201008)
			(end 0.105328 -0.198992)
			(stroke
				(width 0.1)
				(type solid)
			)
			(layer "F.SilkS")
		)
		(fp_line
			(start 0.105328 0.201008)
			(end -0.094672 0.001008)
			(stroke
				(width 0.1)
				(type solid)
			)
			(layer "F.SilkS")
		)
		(fp_line
			(start 0.105328 0.001008)
			(end 0.24 0.001)
			(stroke
				(width 0.1)
				(type solid)
			)
			(layer "F.SilkS")
		)
		(fp_line
			(start -0.094672 0.201008)
			(end -0.094672 -0.198992)
			(stroke
				(width 0.1)
				(type solid)
			)
			(layer "F.SilkS")
		)
		(fp_line
			(start -0.094672 0.001008)
			(end 0.105328 -0.198992)
			(stroke
				(width 0.1)
				(type solid)
			)
			(layer "F.SilkS")
		)
		(fp_line
			(start -0.094672 0.001008)
			(end -0.24 0.001008)
			(stroke
				(width 0.1)
				(type solid)
			)
			(layer "F.SilkS")
		)
		(fp_line
			(start -1.18 -0.319)
			(end -1.18 0.321)
			(stroke
				(width 0.15)
				(type solid)
			)
			(layer "F.SilkS")
		)
		(fp_rect
			(start 1.25 0.65)
			(end -1.25 -0.65)
			(stroke
				(width 0.05)
				(type solid)
			)
			(fill no)
			(layer "F.CrtYd")
		)
		(fp_line
			(start 0.599 0)
			(end 0.201 0)
			(stroke
				(width 0.15)
				(type solid)
			)
			(layer "F.Fab")
		)
		(fp_line
			(start 0.201 0.2)
			(end 0.201 0)
			(stroke
				(width 0.15)
				(type solid)
			)
			(layer "F.Fab")
		)
		(fp_line
			(start 0.201 0)
			(end 0.201 -0.202)
			(stroke
				(width 0.15)
				(type solid)
			)
			(layer "F.Fab")
		)
		(fp_line
			(start 0.201 -0.202)
			(end -0.101 0)
			(stroke
				(width 0.15)
				(type solid)
			)
			(layer "F.Fab")
		)
		(fp_line
			(start -0.101 0)
			(end 0.201 0.2)
			(stroke
				(width 0.15)
				(type solid)
			)
			(layer "F.Fab")
		)
		(fp_line
			(start -0.199 0.2)
			(end -0.199 0.1)
			(stroke
				(width 0.15)
				(type solid)
			)
			(layer "F.Fab")
		)
		(fp_line
			(start -0.199 0)
			(end -0.597 0)
			(stroke
				(width 0.15)
				(type solid)
			)
			(layer "F.Fab")
		)
		(fp_line
			(start -0.199 -0.202)
			(end -0.199 0.1)
			(stroke
				(width 0.15)
				(type solid)
			)
			(layer "F.Fab")
		)
		(fp_rect
			(start 0.848 0.4)
			(end -0.85 -0.402)
			(stroke
				(width 0.15)
				(type solid)
			)
			(fill no)
			(layer "F.Fab")
		)
		(pad "1" smd roundrect
			(at -0.7 0)
			(size 0.8 1)
			(layers "F.Cu" "F.Mask" "F.Paste")
			(roundrect_rratio 0.2)
			(net 930 "Net-(D5-C)")
			(pinfunction "C")
			(pintype "passive")
			(teardrops
				(best_length_ratio 0.2)
				(max_length 1)
				(best_width_ratio 0.9)
				(max_width 2)
				(curved_edges yes)
				(filter_ratio 0.9)
				(enabled yes)
				(allow_two_segments yes)
				(prefer_zone_connections yes)
			)
		)
		(pad "2" smd roundrect
			(at 0.7 0)
			(size 0.8 1)
			(layers "F.Cu" "F.Mask" "F.Paste")
			(roundrect_rratio 0.2)
			(net 2 "+3V3")
			(pinfunction "A")
			(pintype "passive")
			(teardrops
				(best_length_ratio 0.2)
				(max_length 1)
				(best_width_ratio 0.9)
				(max_width 2)
				(curved_edges yes)
				(filter_ratio 0.9)
				(enabled yes)
				(allow_two_segments yes)
				(prefer_zone_connections yes)
			)
		)
	)
	(footprint "antmicro-footprints:R_0402_1005Metric"
		(layer "F.Cu")
		(at 222.68 127.195)
		(descr "Resistor SMD 0402")
		(tags "resistor SMD 0402")
		(property "Reference" "R186"
			(at 0.77 0.465 0)
			(layer "F.SilkS")
			(effects
				(font
					(size 0.7 0.7)
					(thickness 0.15)
				)
				(justify left bottom)
			)
		)
		(property "Value" "R_1k_0402"
			(at -1.011843 1.772047 0)
			(layer "F.Fab")
			(effects
				(font
					(size 0.7 0.7)
					(thickness 0.15)
				)
				(justify left bottom)
			)
		)
		(property "Datasheet" "https://www.bourns.com/docs/product-datasheets/cr.pdf"
			(at 0 0 0)
			(layer "F.Fab")
			(hide yes)
			(effects
				(font
					(size 1.27 1.27)
					(thickness 0.15)
				)
			)
		)
		(property "Author" "Antmicro"
			(at 0 0 0)
			(layer "F.Fab")
			(hide yes)
			(effects
				(font
					(size 1 1)
					(thickness 0.15)
				)
			)
		)
		(property "License" "Apache-2.0"
			(at 0 0 0)
			(layer "F.Fab")
			(hide yes)
			(effects
				(font
					(size 1 1)
					(thickness 0.15)
				)
			)
		)
		(property "MPN" "CR0402-FX-1001GLF"
			(at 0 0 0)
			(layer "F.Fab")
			(hide yes)
			(effects
				(font
					(size 1 1)
					(thickness 0.15)
				)
			)
		)
		(property "Manufacturer" "Bourns"
			(at 0 0 0)
			(layer "F.Fab")
			(hide yes)
			(effects
				(font
					(size 1 1)
					(thickness 0.15)
				)
			)
		)
		(property "Public" "False"
			(at 0 0 0)
			(layer "F.Fab")
			(hide yes)
			(effects
				(font
					(size 1 1)
					(thickness 0.15)
				)
			)
		)
		(property "Tolerance" "1%"
			(at 0 0 0)
			(layer "F.Fab")
			(hide yes)
			(effects
				(font
					(size 1 1)
					(thickness 0.15)
				)
			)
		)
		(property "Val" "1k"
			(at 0 0 0)
			(layer "F.Fab")
			(hide yes)
			(effects
				(font
					(size 1 1)
					(thickness 0.15)
				)
			)
		)
		(sheetname "PCIe misc")
		(sheetfile "pcie_misc.kicad_sch")
		(attr smd)
		(fp_rect
			(start -0.925 -0.47)
			(end 0.925 0.47)
			(stroke
				(width 0.05)
				(type default)
			)
			(fill no)
			(layer "F.CrtYd")
		)
		(fp_rect
			(start -0.5 -0.25)
			(end 0.5 0.25)
			(stroke
				(width 0.15)
				(type solid)
			)
			(fill no)
			(layer "F.Fab")
		)
		(pad "1" smd roundrect
			(at -0.48 0)
			(size 0.59 0.64)
			(layers "F.Cu" "F.Mask" "F.Paste")
			(roundrect_rratio 0.25)
			(net 606 "Net-(U37-~{OE4})")
			(pintype "passive")
			(teardrops
				(best_length_ratio 0.2)
				(max_length 1)
				(best_width_ratio 0.9)
				(max_width 2)
				(curved_edges yes)
				(filter_ratio 0.9)
				(enabled yes)
				(allow_two_segments yes)
				(prefer_zone_connections yes)
			)
		)
		(pad "2" smd roundrect
			(at 0.48 0)
			(size 0.59 0.64)
			(layers "F.Cu" "F.Mask" "F.Paste")
			(roundrect_rratio 0.25)
			(net 1 "GND")
			(pintype "passive")
			(teardrops
				(best_length_ratio 0.2)
				(max_length 1)
				(best_width_ratio 0.9)
				(max_width 2)
				(curved_edges yes)
				(filter_ratio 0.9)
				(enabled yes)
				(allow_two_segments yes)
				(prefer_zone_connections yes)
			)
		)
	)
	(footprint "antmicro-footprints:L_WE-MAPI-4020"
		(layer "F.Cu")
		(at 311.25 125.46 180)
		(property "Reference" "L1"
			(at -2.3 -2.3 0)
			(layer "F.SilkS")
			(effects
				(font
					(size 0.7 0.7)
					(thickness 0.15)
				)
				(justify left bottom)
			)
		)
		(property "Value" "L_1u8_6.8A_WE-MAPI-4020"
			(at -2.4 3.4 0)
			(layer "F.Fab")
			(effects
				(font
					(size 0.7 0.7)
					(thickness 0.15)
				)
				(justify left bottom)
			)
		)
		(property "Datasheet" "https://www.we-online.com/components/products/datasheet/74438356018.pdf"
			(at 0 0 180)
			(layer "F.Fab")
			(hide yes)
			(effects
				(font
					(size 1.27 1.27)
					(thickness 0.15)
				)
			)
		)
		(property "Author" "Antmicro"
			(at 622.5 250.92 0)
			(layer "F.Fab")
			(hide yes)
			(effects
				(font
					(size 1 1)
					(thickness 0.15)
				)
			)
		)
		(property "IMax" "6.8 A"
			(at 622.5 250.92 0)
			(layer "F.Fab")
			(hide yes)
			(effects
				(font
					(size 1 1)
					(thickness 0.15)
				)
			)
		)
		(property "ISat" "6.5 A"
			(at 622.5 250.92 0)
			(layer "F.Fab")
			(hide yes)
			(effects
				(font
					(size 1 1)
					(thickness 0.15)
				)
			)
		)
		(property "License" "Apache-2.0"
			(at 622.5 250.92 0)
			(layer "F.Fab")
			(hide yes)
			(effects
				(font
					(size 1 1)
					(thickness 0.15)
				)
			)
		)
		(property "MPN" "74438356018"
			(at 622.5 250.92 0)
			(layer "F.Fab")
			(hide yes)
			(effects
				(font
					(size 1 1)
					(thickness 0.15)
				)
			)
		)
		(property "Manufacturer" "Würth Elektronik"
			(at 622.5 250.92 0)
			(layer "F.Fab")
			(hide yes)
			(effects
				(font
					(size 1 1)
					(thickness 0.15)
				)
			)
		)
		(property "Public" "False"
			(at 622.5 250.92 0)
			(layer "F.Fab")
			(hide yes)
			(effects
				(font
					(size 1 1)
					(thickness 0.15)
				)
			)
		)
		(property "Size" "4.1x4.1mm"
			(at 622.5 250.92 0)
			(layer "F.Fab")
			(hide yes)
			(effects
				(font
					(size 1 1)
					(thickness 0.15)
				)
			)
		)
		(property "Val" "1u8/6.8A"
			(at 622.5 250.92 0)
			(layer "F.Fab")
			(hide yes)
			(effects
				(font
					(size 1 1)
					(thickness 0.15)
				)
			)
		)
		(sheetname "Power")
		(sheetfile "power.kicad_sch")
		(attr smd)
		(fp_rect
			(start -2.2 -2.2)
			(end 2.2 2.2)
			(stroke
				(width 0.15)
				(type solid)
			)
			(fill no)
			(layer "F.SilkS")
		)
		(fp_rect
			(start -2.3 -2.3)
			(end 2.3 2.3)
			(stroke
				(width 0.05)
				(type solid)
			)
			(fill no)
			(layer "F.CrtYd")
		)
		(fp_rect
			(start -2.05 -2.05)
			(end 2.05 2.05)
			(stroke
				(width 0.15)
				(type solid)
			)
			(fill no)
			(layer "F.Fab")
		)
		(pad "1" smd roundrect
			(at -1.185 0 270)
			(size 3.7 1)
			(layers "F.Cu" "F.Mask" "F.Paste")
			(roundrect_rratio 0.1)
			(net 67 "Net-(C47-Pad2)")
			(pintype "passive")
			(teardrops
				(best_length_ratio 0.2)
				(max_length 1)
				(best_width_ratio 0.9)
				(max_width 2)
				(curved_edges yes)
				(filter_ratio 0.9)
				(enabled yes)
				(allow_two_segments yes)
				(prefer_zone_connections yes)
			)
		)
		(pad "2" smd roundrect
			(at 1.185 0 270)
			(size 3.7 1)
			(layers "F.Cu" "F.Mask" "F.Paste")
			(roundrect_rratio 0.1)
			(net 70 "Net-(C49-Pad2)")
			(pintype "passive")
			(teardrops
				(best_length_ratio 0.2)
				(max_length 1)
				(best_width_ratio 0.9)
				(max_width 2)
				(curved_edges yes)
				(filter_ratio 0.9)
				(enabled yes)
				(allow_two_segments yes)
				(prefer_zone_connections yes)
			)
		)
	)
	(footprint "antmicro-footprints:R_0805_2012Metric"
		(layer "F.Cu")
		(at 304.25 100.64 180)
		(property "Reference" "R104"
			(at -1.55 0.93 0)
			(layer "F.SilkS")
			(effects
				(font
					(size 0.7 0.7)
					(thickness 0.15)
				)
				(justify right bottom)
			)
		)
		(property "Value" "R_0R001_0805"
			(at 1.82 2.18 0)
			(layer "F.Fab")
			(effects
				(font
					(size 0.7 0.7)
					(thickness 0.15)
				)
				(justify left bottom mirror)
			)
		)
		(property "Datasheet" "https://www.eaton.com/content/dam/eaton/products/electronic-components/resources/data-sheet/eaton-msma-automotive-smd-current-sense-resistor-metal-strip-data-sheet-elx1179.pdf"
			(at 0 0 180)
			(layer "F.Fab")
			(hide yes)
			(effects
				(font
					(size 1.27 1.27)
					(thickness 0.15)
				)
			)
		)
		(property "Author" "Antmicro"
			(at 608.5 201.28 0)
			(layer "F.Fab")
			(hide yes)
			(effects
				(font
					(size 1 1)
					(thickness 0.15)
				)
			)
		)
		(property "License" "Apache-2.0"
			(at 608.5 201.28 0)
			(layer "F.Fab")
			(hide yes)
			(effects
				(font
					(size 1 1)
					(thickness 0.15)
				)
			)
		)
		(property "MPN" "MSMA0805R0010FSM"
			(at 608.5 201.28 0)
			(layer "F.Fab")
			(hide yes)
			(effects
				(font
					(size 1 1)
					(thickness 0.15)
				)
			)
		)
		(property "Manufacturer" "Eaton"
			(at 608.5 201.28 0)
			(layer "F.Fab")
			(hide yes)
			(effects
				(font
					(size 1 1)
					(thickness 0.15)
				)
			)
		)
		(property "Public" "False"
			(at 608.5 201.28 0)
			(layer "F.Fab")
			(hide yes)
			(effects
				(font
					(size 1 1)
					(thickness 0.15)
				)
			)
		)
		(property "Tolerance" "1%"
			(at 608.5 201.28 0)
			(layer "F.Fab")
			(hide yes)
			(effects
				(font
					(size 1 1)
					(thickness 0.15)
				)
			)
		)
		(property "Val" "0R001"
			(at 608.5 201.28 0)
			(layer "F.Fab")
			(hide yes)
			(effects
				(font
					(size 1 1)
					(thickness 0.15)
				)
			)
		)
		(sheetname "Power")
		(sheetfile "power.kicad_sch")
		(attr smd)
		(fp_line
			(start -0.3 -0.701)
			(end 0.298 -0.701)
			(stroke
				(width 0.15)
				(type solid)
			)
			(layer "F.SilkS")
		)
		(fp_line
			(start -0.32 0.699)
			(end 0.28 0.699)
			(stroke
				(width 0.15)
				(type solid)
			)
			(layer "F.SilkS")
		)
		(fp_rect
			(start 1.95 -0.9)
			(end -1.95 0.9)
			(stroke
				(width 0.05)
				(type default)
			)
			(fill no)
			(layer "F.CrtYd")
		)
		(fp_line
			(start 0.949 -0.677)
			(end 0.949 0.675)
			(stroke
				(width 0.15)
				(type solid)
			)
			(layer "F.Fab")
		)
		(fp_line
			(start -0.951 0.68)
			(end 0.949 0.68)
			(stroke
				(width 0.15)
				(type solid)
			)
			(layer "F.Fab")
		)
		(fp_line
			(start -0.951 -0.677)
			(end -0.951 0.675)
			(stroke
				(width 0.15)
				(type solid)
			)
			(layer "F.Fab")
		)
		(fp_line
			(start -0.951 -0.682)
			(end 0.949 -0.682)
			(stroke
				(width 0.15)
				(type solid)
			)
			(layer "F.Fab")
		)
		(pad "1" smd roundrect
			(at -1.1 0 180)
			(size 1.2 1.3)
			(layers "F.Cu" "F.Mask" "F.Paste")
			(roundrect_rratio 0.25)
			(net 71 "Net-(U49-IN+)")
			(pintype "passive")
			(teardrops
				(best_length_ratio 0.2)
				(max_length 1)
				(best_width_ratio 0.9)
				(max_width 2)
				(curved_edges yes)
				(filter_ratio 0.9)
				(enabled yes)
				(allow_two_segments yes)
				(prefer_zone_connections yes)
			)
		)
		(pad "2" smd roundrect
			(at 1.1 0 180)
			(size 1.2 1.3)
			(layers "F.Cu" "F.Mask" "F.Paste")
			(roundrect_rratio 0.25)
			(net 2 "+3V3")
			(pintype "passive")
			(teardrops
				(best_length_ratio 0.2)
				(max_length 1)
				(best_width_ratio 0.9)
				(max_width 2)
				(curved_edges yes)
				(filter_ratio 0.9)
				(enabled yes)
				(allow_two_segments yes)
				(prefer_zone_connections yes)
			)
		)
	)
)
